# T6G (Grand Teton) — schematic netlist excerpt (pin names and nets, part order shuffled) for the footprints in the layout excerpt that follows; sources: Cadence DE-HDL packaged netlist, KiCad conversion of 04192023_DAF0TMB3IC0_F0TG_MB_C_brd_V02_OCP.brd

R1163  Q_RES  0 5% CHIP  pkg 0402LF  page 142 : A = HP_LVC3_OCP_V3_2_P12V_PWRGD ; B = HP_LVC3_OCP_V3_2_P12V_R_PWRGD
R9015  Q_RES  100K 1% EMPTY  pkg 0402LF  page 123 : A = PRSNT_CABLE_GPU_A3_N ; B = GND

(kicad_pcb
	(version 20260206)
	(generator "pcbnew")
	(generator_version "10.0")
	(general
		(thickness 1.6)
		(legacy_teardrops no)
	)
	(paper "A4")
	(title_block
		(title "04192023_DAF0TMB3IC0_F0TG_MB_C_brd_V02_OCP.brd")
		(comment 1 "Grand Teton / footprints 2358-2359 of 8354")
	)
	(layers
		(0 "F.Cu" signal "TOP")
		(4 "In1.Cu" signal "GND")
		(6 "In2.Cu" signal "IN1")
		(8 "In3.Cu" signal "GND1")
		(10 "In4.Cu" signal "IN2")
		(12 "In5.Cu" signal "GND2")
		(14 "In6.Cu" signal "IN3")
		(16 "In7.Cu" signal "GND3")
		(18 "In8.Cu" signal "VCC")
		(20 "In9.Cu" signal "VCC1")
		(22 "In10.Cu" signal "GND4")
		(24 "In11.Cu" signal "IN4")
		(26 "In12.Cu" signal "GND5")
		(28 "In13.Cu" signal "IN5")
		(30 "In14.Cu" signal "GND6")
		(32 "In15.Cu" signal "IN6")
		(34 "In16.Cu" signal "GND7")
		(2 "B.Cu" signal "BOTTOM")
		(9 "F.Adhes" user "F.Adhesive")
		(11 "B.Adhes" user "B.Adhesive")
		(13 "F.Paste" user "Package Geometry/Pastemask Top")
		(15 "B.Paste" user "Package Geometry/Pastemask Bottom")
		(5 "F.SilkS" user "Ref Des/Silkscreen Top")
		(7 "B.SilkS" user "Ref Des/Silkscreen Bottom")
		(1 "F.Mask" user "Board Geometry/Soldermask Top")
		(3 "B.Mask" user "Board Geometry/Soldermask Bottom")
		(17 "Dwgs.User" user "User.Drawings")
		(19 "Cmts.User" user "User.Comments")
		(21 "Eco1.User" user "User.Eco1")
		(23 "Eco2.User" user "User.Eco2")
		(25 "Edge.Cuts" user "Board Geometry/Outline")
		(27 "Margin" user)
		(31 "F.CrtYd" user "Package Geometry/Place Bound Top")
		(29 "B.CrtYd" user "Package Geometry/Place Bound Bottom")
		(35 "F.Fab" user "Ref Des/Assembly Top")
		(33 "B.Fab" user "Ref Des/Assembly Bottom")
	)
	(footprint ""
		(layer "F.Cu")
		(at 91.313 -78.105)
		(property "Reference" "R1163"
			(at 0 0 0)
			(layer "F.SilkS")
			(hide yes)
			(effects
				(font
					(size 1.27 1.27)
				)
			)
		)
		(property "Value" ""
			(at 0 0 0)
			(layer "F.Fab")
			(effects
				(font
					(size 1.27 1.27)
				)
			)
		)
		(duplicate_pad_numbers_are_jumpers no)
		(fp_line
			(start -0.7874 -0.4064)
			(end 0.7874 -0.4064)
			(stroke
				(width 0.1524)
				(type default)
			)
			(layer "F.SilkS")
		)
		(fp_line
			(start -0.7874 0.4064)
			(end -0.7874 -0.4064)
			(stroke
				(width 0.1524)
				(type default)
			)
			(layer "F.SilkS")
		)
		(fp_line
			(start 0.7874 -0.4064)
			(end 0.7874 0.4064)
			(stroke
				(width 0.1524)
				(type default)
			)
			(layer "F.SilkS")
		)
		(fp_line
			(start 0.7874 0.4064)
			(end -0.7874 0.4064)
			(stroke
				(width 0.1524)
				(type default)
			)
			(layer "F.SilkS")
		)
		(fp_line
			(start -0.67945 -0.305054)
			(end -0.12065 -0.305054)
			(stroke
				(width 0.1)
				(type default)
			)
			(layer "F.Fab")
		)
		(fp_line
			(start -0.67945 0.3048)
			(end -0.67945 -0.305054)
			(stroke
				(width 0.1)
				(type default)
			)
			(layer "F.Fab")
		)
		(fp_line
			(start -0.12065 -0.305054)
			(end -0.12065 -0.2794)
			(stroke
				(width 0.1)
				(type default)
			)
			(layer "F.Fab")
		)
		(fp_line
			(start -0.12065 -0.2794)
			(end 0.12065 -0.2794)
			(stroke
				(width 0.1)
				(type default)
			)
			(layer "F.Fab")
		)
		(fp_line
			(start -0.12065 0.2794)
			(end -0.12065 0.3048)
			(stroke
				(width 0.1)
				(type default)
			)
			(layer "F.Fab")
		)
		(fp_line
			(start -0.12065 0.3048)
			(end -0.67945 0.3048)
			(stroke
				(width 0.1)
				(type default)
			)
			(layer "F.Fab")
		)
		(fp_line
			(start 0.120396 0.2794)
			(end -0.12065 0.2794)
			(stroke
				(width 0.1)
				(type default)
			)
			(layer "F.Fab")
		)
		(fp_line
			(start 0.120396 0.3048)
			(end 0.120396 0.2794)
			(stroke
				(width 0.1)
				(type default)
			)
			(layer "F.Fab")
		)
		(fp_line
			(start 0.12065 -0.3048)
			(end 0.67945 -0.3048)
			(stroke
				(width 0.1)
				(type default)
			)
			(layer "F.Fab")
		)
		(fp_line
			(start 0.12065 -0.2794)
			(end 0.12065 -0.3048)
			(stroke
				(width 0.1)
				(type default)
			)
			(layer "F.Fab")
		)
		(fp_line
			(start 0.67945 -0.3048)
			(end 0.67945 0.3048)
			(stroke
				(width 0.1)
				(type default)
			)
			(layer "F.Fab")
		)
		(fp_line
			(start 0.67945 0.3048)
			(end 0.120396 0.3048)
			(stroke
				(width 0.1)
				(type default)
			)
			(layer "F.Fab")
		)
		(pad "1" smd circle
			(at -0.40005 0)
			(size 0 0)
			(layers "F.Cu" "F.Mask" "F.Paste")
			(net "HP_LVC3_OCP_V3_2_P12V_PWRGD")
		)
		(pad "2" smd circle
			(at 0.40005 0)
			(size 0 0)
			(layers "F.Cu" "F.Mask" "F.Paste")
			(net "HP_LVC3_OCP_V3_2_P12V_R_PWRGD")
		)
	)
	(footprint ""
		(layer "F.Cu")
		(at 362.025438 -408.915616 180)
		(property "Reference" "R9015"
			(at 0 0 180)
			(layer "F.SilkS")
			(hide yes)
			(effects
				(font
					(size 1.27 1.27)
				)
			)
		)
		(property "Value" ""
			(at 0 0 180)
			(layer "F.Fab")
			(effects
				(font
					(size 1.27 1.27)
				)
			)
		)
		(duplicate_pad_numbers_are_jumpers no)
		(fp_line
			(start 0.7874 0.4064)
			(end -0.7874 0.4064)
			(stroke
				(width 0.1524)
				(type default)
			)
			(layer "F.SilkS")
		)
		(fp_line
			(start 0.7874 -0.4064)
			(end 0.7874 0.4064)
			(stroke
				(width 0.1524)
				(type default)
			)
			(layer "F.SilkS")
		)
		(fp_line
			(start -0.7874 0.4064)
			(end -0.7874 -0.4064)
			(stroke
				(width 0.1524)
				(type default)
			)
			(layer "F.SilkS")
		)
		(fp_line
			(start -0.7874 -0.4064)
			(end 0.7874 -0.4064)
			(stroke
				(width 0.1524)
				(type default)
			)
			(layer "F.SilkS")
		)
		(fp_line
			(start 0.67945 0.3048)
			(end 0.120396 0.3048)
			(stroke
				(width 0.1)
				(type default)
			)
			(layer "F.Fab")
		)
		(fp_line
			(start 0.67945 -0.3048)
			(end 0.67945 0.3048)
			(stroke
				(width 0.1)
				(type default)
			)
			(layer "F.Fab")
		)
		(fp_line
			(start 0.12065 -0.2794)
			(end 0.12065 -0.3048)
			(stroke
				(width 0.1)
				(type default)
			)
			(layer "F.Fab")
		)
		(fp_line
			(start 0.12065 -0.3048)
			(end 0.67945 -0.3048)
			(stroke
				(width 0.1)
				(type default)
			)
			(layer "F.Fab")
		)
		(fp_line
			(start 0.120396 0.3048)
			(end 0.120396 0.2794)
			(stroke
				(width 0.1)
				(type default)
			)
			(layer "F.Fab")
		)
		(fp_line
			(start 0.120396 0.2794)
			(end -0.12065 0.2794)
			(stroke
				(width 0.1)
				(type default)
			)
			(layer "F.Fab")
		)
		(fp_line
			(start -0.12065 0.3048)
			(end -0.67945 0.3048)
			(stroke
				(width 0.1)
				(type default)
			)
			(layer "F.Fab")
		)
		(fp_line
			(start -0.12065 0.2794)
			(end -0.12065 0.3048)
			(stroke
				(width 0.1)
				(type default)
			)
			(layer "F.Fab")
		)
		(fp_line
			(start -0.12065 -0.2794)
			(end 0.12065 -0.2794)
			(stroke
				(width 0.1)
				(type default)
			)
			(layer "F.Fab")
		)
		(fp_line
			(start -0.12065 -0.305054)
			(end -0.12065 -0.2794)
			(stroke
				(width 0.1)
				(type default)
			)
			(layer "F.Fab")
		)
		(fp_line
			(start -0.67945 0.3048)
			(end -0.67945 -0.305054)
			(stroke
				(width 0.1)
				(type default)
			)
			(layer "F.Fab")
		)
		(fp_line
			(start -0.67945 -0.305054)
			(end -0.12065 -0.305054)
			(stroke
				(width 0.1)
				(type default)
			)
			(layer "F.Fab")
		)
		(pad "1" smd circle
			(at -0.40005 0 180)
			(size 0 0)
			(layers "F.Cu" "F.Mask" "F.Paste")
			(net "PRSNT_CABLE_GPU_A3_N")
		)
		(pad "2" smd circle
			(at 0.40005 0 180)
			(size 0 0)
			(layers "F.Cu" "F.Mask" "F.Paste")
			(net "GND")
		)
	)
)
